# S9S_MB_2U (Grand Teton) — schematic netlist excerpt (pin names and nets, part order shuffled) for the footprints in the layout excerpt that follows; sources: Cadence DE-HDL packaged netlist, KiCad conversion of 03242023_DA0F0TMBIJ0_F0T_Motherboard_J_brd_V01_OCP.brd

J35  SCONN168_ME1016810202011  IO  pkg CON_F168S2H7D_P0-6W2-95_LUH  page 159
  GND_A1  = GND
  GND_A2  = GND
  GND_A3  = GND
  GND_A4  = GND
  GND_A5  = GND
  GND_A6  = GND
  SMCLK  = SMB_OCP_V3_2_3V3AUX_BUF_R_SCL
  SMDAT  = SMB_OCP_V3_2_3V3AUX_BUF_R_SDA
  \smrst#\  = RST_SMB_OCP_V3_2_N
  \prsnta#\  = OCP_V3_1_PRSNTA_R_N
  \perst1#\  = RST_PERST1_OCP_V3_2_N
  \prsntb2#\  = OCP_V3_2_PRSNT2_R_N
  GND_A13  = GND
  REFCLKN1  = CLK_100M_OCP_V3_2_B_DN
  REFCLKP1  = CLK_100M_OCP_V3_2_B_DP
  GND_A16  = GND
  PERN0  = P5E_CPU1_PE1_RX_DN<0>
  PERP0  = P5E_CPU1_PE1_RX_DP<0>
  GND_A19  = GND
  PERN1  = P5E_CPU1_PE1_RX_DN<1>
  PERP1  = P5E_CPU1_PE1_RX_DP<1>
  GND_A22  = GND
  PERN2  = P5E_CPU1_PE1_RX_DN<2>
  PERP2  = P5E_CPU1_PE1_RX_DP<2>
  GND_A25  = GND
  PERN3  = P5E_CPU1_PE1_RX_DN<3>
  PERP3  = P5E_CPU1_PE1_RX_DP<3>
  GND_A28  = GND
  GND_A29  = GND
  PERN4  = P5E_CPU1_PE1_RX_DN<4>
  PERP4  = P5E_CPU1_PE1_RX_DP<4>
  GND_A32  = GND
  PERN5  = P5E_CPU1_PE1_RX_DN<5>
  PERP5  = P5E_CPU1_PE1_RX_DP<5>
  GND_A35  = GND
  PERN6  = P5E_CPU1_PE1_RX_DN<6>
  PERP6  = P5E_CPU1_PE1_RX_DP<6>
  GND_A38  = GND
  PERN7  = P5E_CPU1_PE1_RX_DN<7>
  PERP7  = P5E_CPU1_PE1_RX_DP<7>
  GND_A41  = GND
  \prsntb1#\  = OCP_V3_2_PRSNT1_R_N
  GND_A43  = GND
  PERN8  = P5E_CPU1_PE1_RX_DN<8>
  PERP8  = P5E_CPU1_PE1_RX_DP<8>
  GND_A46  = GND
  PERN9  = P5E_CPU1_PE1_RX_DN<9>
  PERP9  = P5E_CPU1_PE1_RX_DP<9>
  GND_A49  = GND
  PERN10  = P5E_CPU1_PE1_RX_DN<10>
  PERP10  = P5E_CPU1_PE1_RX_DP<10>
  GND_A52  = GND
  PERN11  = P5E_CPU1_PE1_RX_DN<11>
  PERP11  = P5E_CPU1_PE1_RX_DP<11>
  GND_A55  = GND
  PERN12  = P5E_CPU1_PE1_RX_DN<12>
  PERP12  = P5E_CPU1_PE1_RX_DP<12>
  GND_A58  = GND
  PERN13  = P5E_CPU1_PE1_RX_DN<13>
  PERP13  = P5E_CPU1_PE1_RX_DP<13>
  GND_A61  = GND
  PERN14  = P5E_CPU1_PE1_RX_DN<14>
  PERP14  = P5E_CPU1_PE1_RX_DP<14>
  GND_A64  = GND
  PERN15  = P5E_CPU1_PE1_RX_DN<15>
  PERP15  = P5E_CPU1_PE1_RX_DP<15>
  GND_A67  = GND
  USB_DATN  = USB2_5_R1_DN
  USB_DATP  = USB2_5_R1_DP
  \pwrbrk0#\  = OCP_V3_2_PWRBRK_N
  \+12v_edge_b1\  = P12V_OCP_V3_2
  \+12v_edge_b2\  = P12V_OCP_V3_2
  \+12v_edge_b3\  = P12V_OCP_V3_2
  \+12v_edge_b4\  = P12V_OCP_V3_2
  \+12v_edge_b5\  = P12V_OCP_V3_2
  \+12v_edge_b6\  = P12V_OCP_V3_2
  \bif0#\  = OCP_V3_2_BIF0_R_N
  \bif1#\  = OCP_V3_2_BIF1_R_N
  \bif2#\  = OCP_V3_2_BIF2_R_N
  \perst0#\  = RST_PERST0_OCP_V3_2_N
  \+3.3v_edge\  = P3V3_OCP_V3_2
  AUX_PWR_EN  = OCP_V3_2_AUX_PWR_EN_R
  GND_B13  = GND
  REFCLKN0  = CLK_100M_OCP_V3_2_A_DN
  REFCLKP0  = CLK_100M_OCP_V3_2_A_DP
  GND_B16  = GND
  PETN0  = P5E_CPU1_PE1_TX_C_DP<0>
  PETP0  = P5E_CPU1_PE1_TX_C_DN<0>
  GND_B19  = GND
  PETN1  = P5E_CPU1_PE1_TX_C_DN<1>
  PETP1  = P5E_CPU1_PE1_TX_C_DP<1>
  GND_B22  = GND
  PETN2  = P5E_CPU1_PE1_TX_C_DP<2>
  PETP2  = P5E_CPU1_PE1_TX_C_DN<2>
  GND_B25  = GND
  PETN3  = P5E_CPU1_PE1_TX_C_DN<3>
  PETP3  = P5E_CPU1_PE1_TX_C_DP<3>
  GND_B28  = GND
  GND_B29  = GND
  PETN4  = P5E_CPU1_PE1_TX_C_DP<4>
  PETP4  = P5E_CPU1_PE1_TX_C_DN<4>
  GND_B32  = GND
  PETN5  = P5E_CPU1_PE1_TX_C_DN<5>
  PETP5  = P5E_CPU1_PE1_TX_C_DP<5>
  GND_B35  = GND
  PETN6  = P5E_CPU1_PE1_TX_C_DP<6>
  PETP6  = P5E_CPU1_PE1_TX_C_DN<6>
  GND_B38  = GND
  PETN7  = P5E_CPU1_PE1_TX_C_DN<7>
  PETP7  = P5E_CPU1_PE1_TX_C_DP<7>
  GND_B41  = GND
  \prsntb0#\  = OCP_V3_2_PRSNT0_R_N
  GND_B43  = GND
  PETN8  = P5E_CPU1_PE1_TX_C_DP<8>
  PETP8  = P5E_CPU1_PE1_TX_C_DN<8>
  GND_B46  = GND
  PETN9  = P5E_CPU1_PE1_TX_C_DN<9>
  PETP9  = P5E_CPU1_PE1_TX_C_DP<9>
  GND_B49  = GND
  PETN10  = P5E_CPU1_PE1_TX_C_DP<10>
  PETP10  = P5E_CPU1_PE1_TX_C_DN<10>
  GND_B52  = GND
  PETN11  = P5E_CPU1_PE1_TX_C_DN<11>
  PETP11  = P5E_CPU1_PE1_TX_C_DP<11>
  GND_B55  = GND
  PETN12  = P5E_CPU1_PE1_TX_C_DP<12>
  PETP12  = P5E_CPU1_PE1_TX_C_DN<12>
  GND_B58  = GND
  PETN13  = P5E_CPU1_PE1_TX_C_DN<13>
  PETP13  = P5E_CPU1_PE1_TX_C_DP<13>
  GND_B61  = GND
  PETN14  = P5E_CPU1_PE1_TX_C_DP<14>
  PETP14  = P5E_CPU1_PE1_TX_C_DN<14>
  GND_B64  = GND
  PETN15  = P5E_CPU1_PE1_TX_C_DN<15>
  PETP15  = P5E_CPU1_PE1_TX_C_DP<15>
  GND_B67  = GND
  RFU1_NC_B68  = TP_OCP_V3_2_B68
  RFU1_NC_B69  = TP_OCP_V3_2_B69
  \prsntb3#\  = OCP_V3_2_PRSNT3_R_N
  G1  = GND
  G2  = GND
  G3  = GND
  G4  = GND
  G5  = GND
  \perst2#\  = RST_PERST2_OCP_V3_2_N
  \perst3#\  = RST_PERST3_OCP_V3_2_N
  \wake#\  = IRQ_LVC3_OCP_V3_2_WAKE_N
  RBT_ARB_IN  = OCP_V3_2_ISO1_RBT_ARB_IN
  RBT_ARB_OUT  = OCP_V3_2_ISO2_RBT_ARB_OUT
  SLOT_ID1  = OCP_V3_2_ID1
  RBT_TX_EN  = NCSI_OCP_V3_2_TX_EN
  RBT_TXD1  = NCSI_OCP_V3_2_TXD1
  RBT_TXD0  = NCSI_OCP_V3_2_TXD0
  GND_OA10  = GND
  REFCLKN3  = CLK_100M_OCP_V3_2_D_DN
  REFCLKP3  = CLK_100M_OCP_V3_2_D_DP
  GND_OA13  = GND
  RBT_CLK_IN  = CLK_50M_NCSI_OCP_V3_2_ISO
  NIC_PWR_GOOD  = FM_OCP_V3_2_PWR_GOOD
  MAIN_PWR_EN  = OCP_V3_2_MAIN_PWR_EN_R
  \ld#\  = SGPIO_OCP_V3_2_LD_N
  DATA_IN  = SGPIO_OCP_V3_2_DATAIN
  DATA_OUT  = SGPIO_OCP_V3_2_DATAOUT
  CLK  = SGPIO_OCP_V3_2_CLK
  SLOT_ID0  = OCP_V3_2_ID0
  RBT_RXD1  = NCSI_OCP_V3_2_RXD1
  RBT_RXD0  = NCSI_OCP_V3_2_RXD0
  GND_OB10  = GND
  REFCLKN2  = CLK_100M_OCP_V3_2_C_DN
  REFCLKP2  = CLK_100M_OCP_V3_2_C_DP
  GND_OB13  = GND
  RBT_CRS_DV  = NCSI_OCP_V3_2_CRS_DV

(kicad_pcb
	(version 20260206)
	(generator "pcbnew")
	(generator_version "10.0")
	(general
		(thickness 1.6)
		(legacy_teardrops no)
	)
	(paper "A4")
	(title_block
		(title "03242023_DA0F0TMBIJ0_F0T_Motherboard_J_brd_V01_OCP.brd")
		(comment 1 "Grand Teton / footprint 3456 of 6105 (J35), pads 89-132 of 175")
	)
	(layers
		(0 "F.Cu" signal "TOP")
		(4 "In1.Cu" signal "GND")
		(6 "In2.Cu" signal "IN1")
		(8 "In3.Cu" signal "GND1")
		(10 "In4.Cu" signal "IN2")
		(12 "In5.Cu" signal "GND2")
		(14 "In6.Cu" signal "IN3")
		(16 "In7.Cu" signal "GND3")
		(18 "In8.Cu" signal "VCC")
		(20 "In9.Cu" signal "VCC1")
		(22 "In10.Cu" signal "GND4")
		(24 "In11.Cu" signal "IN4")
		(26 "In12.Cu" signal "GND5")
		(28 "In13.Cu" signal "IN5")
		(30 "In14.Cu" signal "GND6")
		(32 "In15.Cu" signal "IN6")
		(34 "In16.Cu" signal "GND7")
		(2 "B.Cu" signal "BOTTOM")
		(9 "F.Adhes" user "F.Adhesive")
		(11 "B.Adhes" user "B.Adhesive")
		(13 "F.Paste" user "Package Geometry/Pastemask Top")
		(15 "B.Paste" user "Package Geometry/Pastemask Bottom")
		(5 "F.SilkS" user "Ref Des/Silkscreen Top")
		(7 "B.SilkS" user "Ref Des/Silkscreen Bottom")
		(1 "F.Mask" user "Board Geometry/Soldermask Top")
		(3 "B.Mask" user "Board Geometry/Soldermask Bottom")
		(17 "Dwgs.User" user "User.Drawings")
		(19 "Cmts.User" user "User.Comments")
		(21 "Eco1.User" user "User.Eco1")
		(23 "Eco2.User" user "User.Eco2")
		(25 "Edge.Cuts" user "Board Geometry/Outline")
		(27 "Margin" user)
		(31 "F.CrtYd" user "Package Geometry/Place Bound Top")
		(29 "B.CrtYd" user "Package Geometry/Place Bound Bottom")
		(35 "F.Fab" user "Ref Des/Assembly Top")
		(33 "B.Fab" user "Ref Des/Assembly Bottom")
	)
	(footprint ""
		(layer "F.Cu")
		(at 47.401988 -5.569966 -90)
		(property "Reference" "J35"
			(at -16.848074 29.242004 0)
			(unlocked yes)
			(layer "F.SilkS")
			(effects
				(font
					(size 0.7874 0.5842)
					(thickness 0.1524)
				)
				(justify left)
			)
		)
		(property "Value" ""
			(at 0 0 270)
			(layer "F.Fab")
			(effects
				(font
					(size 1.27 1.27)
				)
			)
		)
		(duplicate_pad_numbers_are_jumpers no)
		(pad "B17" smd rect
			(at -5.700014 -8.865108 180)
			(size 0.381 1.4478)
			(layers "F.Cu" "F.Mask" "F.Paste")
			(net "P5E_CPU1_PE1_TX_C_DP<0>")
		)
		(pad "B18" smd rect
			(at -5.700014 -8.264906 180)
			(size 0.381 1.4478)
			(layers "F.Cu" "F.Mask" "F.Paste")
			(net "P5E_CPU1_PE1_TX_C_DN<0>")
		)
		(pad "B19" smd rect
			(at -5.700014 -7.664958 180)
			(size 0.381 1.4478)
			(layers "F.Cu" "F.Mask" "F.Paste")
			(net "GND")
		)
		(pad "B20" smd rect
			(at -5.700014 -7.06501 180)
			(size 0.381 1.4478)
			(layers "F.Cu" "F.Mask" "F.Paste")
			(net "P5E_CPU1_PE1_TX_C_DN<1>")
		)
		(pad "B21" smd rect
			(at -5.700014 -6.465062 180)
			(size 0.381 1.4478)
			(layers "F.Cu" "F.Mask" "F.Paste")
			(net "P5E_CPU1_PE1_TX_C_DP<1>")
		)
		(pad "B22" smd rect
			(at -5.700014 -5.865114 180)
			(size 0.381 1.4478)
			(layers "F.Cu" "F.Mask" "F.Paste")
			(net "GND")
		)
		(pad "B23" smd rect
			(at -5.700014 -5.264912 180)
			(size 0.381 1.4478)
			(layers "F.Cu" "F.Mask" "F.Paste")
			(net "P5E_CPU1_PE1_TX_C_DP<2>")
		)
		(pad "B24" smd rect
			(at -5.700014 -4.664964 180)
			(size 0.381 1.4478)
			(layers "F.Cu" "F.Mask" "F.Paste")
			(net "P5E_CPU1_PE1_TX_C_DN<2>")
		)
		(pad "B25" smd rect
			(at -5.700014 -4.065016 180)
			(size 0.381 1.4478)
			(layers "F.Cu" "F.Mask" "F.Paste")
			(net "GND")
		)
		(pad "B26" smd rect
			(at -5.700014 -3.465068 180)
			(size 0.381 1.4478)
			(layers "F.Cu" "F.Mask" "F.Paste")
			(net "P5E_CPU1_PE1_TX_C_DN<3>")
		)
		(pad "B27" smd rect
			(at -5.700014 -2.86512 180)
			(size 0.381 1.4478)
			(layers "F.Cu" "F.Mask" "F.Paste")
			(net "P5E_CPU1_PE1_TX_C_DP<3>")
		)
		(pad "B28" smd rect
			(at -5.700014 -2.264918 180)
			(size 0.381 1.4478)
			(layers "F.Cu" "F.Mask" "F.Paste")
			(net "GND")
		)
		(pad "B29" smd rect
			(at -5.700014 1.74498 180)
			(size 0.381 1.4478)
			(layers "F.Cu" "F.Mask" "F.Paste")
			(net "GND")
		)
		(pad "B30" smd rect
			(at -5.700014 2.344928 180)
			(size 0.381 1.4478)
			(layers "F.Cu" "F.Mask" "F.Paste")
			(net "P5E_CPU1_PE1_TX_C_DP<4>")
		)
		(pad "B31" smd rect
			(at -5.700014 2.944876 180)
			(size 0.381 1.4478)
			(layers "F.Cu" "F.Mask" "F.Paste")
			(net "P5E_CPU1_PE1_TX_C_DN<4>")
		)
		(pad "B32" smd rect
			(at -5.700014 3.545078 180)
			(size 0.381 1.4478)
			(layers "F.Cu" "F.Mask" "F.Paste")
			(net "GND")
		)
		(pad "B33" smd rect
			(at -5.700014 4.145026 180)
			(size 0.381 1.4478)
			(layers "F.Cu" "F.Mask" "F.Paste")
			(net "P5E_CPU1_PE1_TX_C_DN<5>")
		)
		(pad "B34" smd rect
			(at -5.700014 4.744974 180)
			(size 0.381 1.4478)
			(layers "F.Cu" "F.Mask" "F.Paste")
			(net "P5E_CPU1_PE1_TX_C_DP<5>")
		)
		(pad "B35" smd rect
			(at -5.700014 5.344922 180)
			(size 0.381 1.4478)
			(layers "F.Cu" "F.Mask" "F.Paste")
			(net "GND")
		)
		(pad "B36" smd rect
			(at -5.700014 5.945124 180)
			(size 0.381 1.4478)
			(layers "F.Cu" "F.Mask" "F.Paste")
			(net "P5E_CPU1_PE1_TX_C_DP<6>")
		)
		(pad "B37" smd rect
			(at -5.700014 6.545072 180)
			(size 0.381 1.4478)
			(layers "F.Cu" "F.Mask" "F.Paste")
			(net "P5E_CPU1_PE1_TX_C_DN<6>")
		)
		(pad "B38" smd rect
			(at -5.700014 7.14502 180)
			(size 0.381 1.4478)
			(layers "F.Cu" "F.Mask" "F.Paste")
			(net "GND")
		)
		(pad "B39" smd rect
			(at -5.700014 7.744968 180)
			(size 0.381 1.4478)
			(layers "F.Cu" "F.Mask" "F.Paste")
			(net "P5E_CPU1_PE1_TX_C_DN<7>")
		)
		(pad "B40" smd rect
			(at -5.700014 8.344916 180)
			(size 0.381 1.4478)
			(layers "F.Cu" "F.Mask" "F.Paste")
			(net "P5E_CPU1_PE1_TX_C_DP<7>")
		)
		(pad "B41" smd rect
			(at -5.700014 8.945118 180)
			(size 0.381 1.4478)
			(layers "F.Cu" "F.Mask" "F.Paste")
			(net "GND")
		)
		(pad "B42" smd rect
			(at -5.700014 9.545066 180)
			(size 0.381 1.4478)
			(layers "F.Cu" "F.Mask" "F.Paste")
			(net "OCP_V3_2_PRSNT0_R_N")
		)
		(pad "B43" smd rect
			(at -5.700014 14.454886 180)
			(size 0.381 1.4478)
			(layers "F.Cu" "F.Mask" "F.Paste")
			(net "GND")
		)
		(pad "B44" smd rect
			(at -5.700014 15.055088 180)
			(size 0.381 1.4478)
			(layers "F.Cu" "F.Mask" "F.Paste")
			(net "P5E_CPU1_PE1_TX_C_DP<8>")
		)
		(pad "B45" smd rect
			(at -5.700014 15.655036 180)
			(size 0.381 1.4478)
			(layers "F.Cu" "F.Mask" "F.Paste")
			(net "P5E_CPU1_PE1_TX_C_DN<8>")
		)
		(pad "B46" smd rect
			(at -5.700014 16.254984 180)
			(size 0.381 1.4478)
			(layers "F.Cu" "F.Mask" "F.Paste")
			(net "GND")
		)
		(pad "B47" smd rect
			(at -5.700014 16.854932 180)
			(size 0.381 1.4478)
			(layers "F.Cu" "F.Mask" "F.Paste")
			(net "P5E_CPU1_PE1_TX_C_DN<9>")
		)
		(pad "B48" smd rect
			(at -5.700014 17.45488 180)
			(size 0.381 1.4478)
			(layers "F.Cu" "F.Mask" "F.Paste")
			(net "P5E_CPU1_PE1_TX_C_DP<9>")
		)
		(pad "B49" smd rect
			(at -5.700014 18.055082 180)
			(size 0.381 1.4478)
			(layers "F.Cu" "F.Mask" "F.Paste")
			(net "GND")
		)
		(pad "B50" smd rect
			(at -5.700014 18.65503 180)
			(size 0.381 1.4478)
			(layers "F.Cu" "F.Mask" "F.Paste")
			(net "P5E_CPU1_PE1_TX_C_DP<10>")
		)
		(pad "B51" smd rect
			(at -5.700014 19.254978 180)
			(size 0.381 1.4478)
			(layers "F.Cu" "F.Mask" "F.Paste")
			(net "P5E_CPU1_PE1_TX_C_DN<10>")
		)
		(pad "B52" smd rect
			(at -5.700014 19.854926 180)
			(size 0.381 1.4478)
			(layers "F.Cu" "F.Mask" "F.Paste")
			(net "GND")
		)
		(pad "B53" smd rect
			(at -5.700014 20.455128 180)
			(size 0.381 1.4478)
			(layers "F.Cu" "F.Mask" "F.Paste")
			(net "P5E_CPU1_PE1_TX_C_DN<11>")
		)
		(pad "B54" smd rect
			(at -5.700014 21.055076 180)
			(size 0.381 1.4478)
			(layers "F.Cu" "F.Mask" "F.Paste")
			(net "P5E_CPU1_PE1_TX_C_DP<11>")
		)
		(pad "B55" smd rect
			(at -5.700014 21.655024 180)
			(size 0.381 1.4478)
			(layers "F.Cu" "F.Mask" "F.Paste")
			(net "GND")
		)
		(pad "B56" smd rect
			(at -5.700014 22.254972 180)
			(size 0.381 1.4478)
			(layers "F.Cu" "F.Mask" "F.Paste")
			(net "P5E_CPU1_PE1_TX_C_DP<12>")
		)
		(pad "B57" smd rect
			(at -5.700014 22.85492 180)
			(size 0.381 1.4478)
			(layers "F.Cu" "F.Mask" "F.Paste")
			(net "P5E_CPU1_PE1_TX_C_DN<12>")
		)
		(pad "B58" smd rect
			(at -5.700014 23.455122 180)
			(size 0.381 1.4478)
			(layers "F.Cu" "F.Mask" "F.Paste")
			(net "GND")
		)
		(pad "B59" smd rect
			(at -5.700014 24.05507 180)
			(size 0.381 1.4478)
			(layers "F.Cu" "F.Mask" "F.Paste")
			(net "P5E_CPU1_PE1_TX_C_DN<13>")
		)
		(pad "B60" smd rect
			(at -5.700014 24.655018 180)
			(size 0.381 1.4478)
			(layers "F.Cu" "F.Mask" "F.Paste")
			(net "P5E_CPU1_PE1_TX_C_DP<13>")
		)
	)
)
